(kicad_pcb
	(version 20260206)
	(generator "pcbnew")
	(generator_version "10.0")
	(general
		(thickness 1.6)
		(legacy_teardrops no)
	)
	(paper "A4")
	(title_block
		(title "04192023_DAF0TMB3IC0_F0TG_MB_C_brd_V02_OCP.brd")
		(comment 1 "Grand Teton / footprints 4982-4988 of 8354")
	)
	(layers
		(0 "F.Cu" signal "TOP")
		(4 "In1.Cu" signal "GND")
		(6 "In2.Cu" signal "IN1")
		(8 "In3.Cu" signal "GND1")
		(10 "In4.Cu" signal "IN2")
		(12 "In5.Cu" signal "GND2")
		(14 "In6.Cu" signal "IN3")
		(16 "In7.Cu" signal "GND3")
		(18 "In8.Cu" signal "VCC")
		(20 "In9.Cu" signal "VCC1")
		(22 "In10.Cu" signal "GND4")
		(24 "In11.Cu" signal "IN4")
		(26 "In12.Cu" signal "GND5")
		(28 "In13.Cu" signal "IN5")
		(30 "In14.Cu" signal "GND6")
		(32 "In15.Cu" signal "IN6")
		(34 "In16.Cu" signal "GND7")
		(2 "B.Cu" signal "BOTTOM")
		(9 "F.Adhes" user "F.Adhesive")
		(11 "B.Adhes" user "B.Adhesive")
		(13 "F.Paste" user "Package Geometry/Pastemask Top")
		(15 "B.Paste" user "Package Geometry/Pastemask Bottom")
		(5 "F.SilkS" user "Ref Des/Silkscreen Top")
		(7 "B.SilkS" user "Ref Des/Silkscreen Bottom")
		(1 "F.Mask" user "Board Geometry/Soldermask Top")
		(3 "B.Mask" user "Board Geometry/Soldermask Bottom")
		(17 "Dwgs.User" user "User.Drawings")
		(19 "Cmts.User" user "User.Comments")
		(21 "Eco1.User" user "User.Eco1")
		(23 "Eco2.User" user "User.Eco2")
		(25 "Edge.Cuts" user "Board Geometry/Outline")
		(27 "Margin" user)
		(31 "F.CrtYd" user "Package Geometry/Place Bound Top")
		(29 "B.CrtYd" user "Package Geometry/Place Bound Bottom")
		(35 "F.Fab" user "Ref Des/Assembly Top")
		(33 "B.Fab" user "Ref Des/Assembly Bottom")
	)
	(footprint ""
		(layer "B.Cu")
		(at 136.040114 -36.882578)
		(property "Reference" "C6036"
			(at 0 0 0)
			(layer "B.SilkS")
			(hide yes)
			(effects
				(font
					(size 1.27 1.27)
				)
				(justify mirror)
			)
		)
		(property "Value" ""
			(at 0 0 0)
			(layer "B.Fab")
			(effects
				(font
					(size 1.27 1.27)
				)
				(justify mirror)
			)
		)
		(duplicate_pad_numbers_are_jumpers no)
		(fp_line
			(start -0.7874 -0.4064)
			(end -0.7874 0.4064)
			(stroke
				(width 0.1524)
				(type default)
			)
			(layer "B.SilkS")
		)
		(fp_line
			(start -0.7874 0.4064)
			(end 0.7874 0.4064)
			(stroke
				(width 0.1524)
				(type default)
			)
			(layer "B.SilkS")
		)
		(fp_line
			(start 0.7874 -0.4064)
			(end -0.7874 -0.4064)
			(stroke
				(width 0.1524)
				(type default)
			)
			(layer "B.SilkS")
		)
		(fp_line
			(start 0.7874 0.4064)
			(end 0.7874 -0.4064)
			(stroke
				(width 0.1524)
				(type default)
			)
			(layer "B.SilkS")
		)
		(fp_line
			(start -0.67945 -0.3048)
			(end -0.67945 0.3048)
			(stroke
				(width 0.1)
				(type default)
			)
			(layer "B.Fab")
		)
		(fp_line
			(start -0.67945 0.3048)
			(end -0.120396 0.3048)
			(stroke
				(width 0.1)
				(type default)
			)
			(layer "B.Fab")
		)
		(fp_line
			(start -0.12065 -0.3048)
			(end -0.67945 -0.3048)
			(stroke
				(width 0.1)
				(type default)
			)
			(layer "B.Fab")
		)
		(fp_line
			(start -0.12065 -0.2794)
			(end -0.12065 -0.3048)
			(stroke
				(width 0.1)
				(type default)
			)
			(layer "B.Fab")
		)
		(fp_line
			(start -0.120396 0.2794)
			(end 0.12065 0.2794)
			(stroke
				(width 0.1)
				(type default)
			)
			(layer "B.Fab")
		)
		(fp_line
			(start -0.120396 0.3048)
			(end -0.120396 0.2794)
			(stroke
				(width 0.1)
				(type default)
			)
			(layer "B.Fab")
		)
		(fp_line
			(start 0.12065 -0.305054)
			(end 0.12065 -0.2794)
			(stroke
				(width 0.1)
				(type default)
			)
			(layer "B.Fab")
		)
		(fp_line
			(start 0.12065 -0.2794)
			(end -0.12065 -0.2794)
			(stroke
				(width 0.1)
				(type default)
			)
			(layer "B.Fab")
		)
		(fp_line
			(start 0.12065 0.2794)
			(end 0.12065 0.3048)
			(stroke
				(width 0.1)
				(type default)
			)
			(layer "B.Fab")
		)
		(fp_line
			(start 0.12065 0.3048)
			(end 0.67945 0.3048)
			(stroke
				(width 0.1)
				(type default)
			)
			(layer "B.Fab")
		)
		(fp_line
			(start 0.67945 -0.305054)
			(end 0.12065 -0.305054)
			(stroke
				(width 0.1)
				(type default)
			)
			(layer "B.Fab")
		)
		(fp_line
			(start 0.67945 0.3048)
			(end 0.67945 -0.305054)
			(stroke
				(width 0.1)
				(type default)
			)
			(layer "B.Fab")
		)
		(pad "1" smd circle
			(at 0.40005 0 180)
			(size 0 0)
			(layers "B.Cu" "B.Mask" "B.Paste")
			(net "P1V2_CPU0_USB_DVDD12")
		)
		(pad "2" smd circle
			(at -0.40005 0 180)
			(size 0 0)
			(layers "B.Cu" "B.Mask" "B.Paste")
			(net "GND")
		)
	)
	(footprint ""
		(layer "B.Cu")
		(at 115.864386 -266.005564)
		(property "Reference" "C2118"
			(at 0 0 0)
			(layer "B.SilkS")
			(hide yes)
			(effects
				(font
					(size 1.27 1.27)
				)
				(justify mirror)
			)
		)
		(property "Value" ""
			(at 0 0 0)
			(layer "B.Fab")
			(effects
				(font
					(size 1.27 1.27)
				)
				(justify mirror)
			)
		)
		(duplicate_pad_numbers_are_jumpers no)
		(fp_line
			(start -0.7874 -0.4064)
			(end -0.7874 0.4064)
			(stroke
				(width 0.1524)
				(type default)
			)
			(layer "B.SilkS")
		)
		(fp_line
			(start -0.7874 0.4064)
			(end 0.7874 0.4064)
			(stroke
				(width 0.1524)
				(type default)
			)
			(layer "B.SilkS")
		)
		(fp_line
			(start 0.7874 -0.4064)
			(end -0.7874 -0.4064)
			(stroke
				(width 0.1524)
				(type default)
			)
			(layer "B.SilkS")
		)
		(fp_line
			(start 0.7874 0.4064)
			(end 0.7874 -0.4064)
			(stroke
				(width 0.1524)
				(type default)
			)
			(layer "B.SilkS")
		)
		(fp_line
			(start -0.67945 -0.3048)
			(end -0.67945 0.3048)
			(stroke
				(width 0.1)
				(type default)
			)
			(layer "B.Fab")
		)
		(fp_line
			(start -0.67945 0.3048)
			(end -0.120396 0.3048)
			(stroke
				(width 0.1)
				(type default)
			)
			(layer "B.Fab")
		)
		(fp_line
			(start -0.12065 -0.3048)
			(end -0.67945 -0.3048)
			(stroke
				(width 0.1)
				(type default)
			)
			(layer "B.Fab")
		)
		(fp_line
			(start -0.12065 -0.2794)
			(end -0.12065 -0.3048)
			(stroke
				(width 0.1)
				(type default)
			)
			(layer "B.Fab")
		)
		(fp_line
			(start -0.120396 0.2794)
			(end 0.12065 0.2794)
			(stroke
				(width 0.1)
				(type default)
			)
			(layer "B.Fab")
		)
		(fp_line
			(start -0.120396 0.3048)
			(end -0.120396 0.2794)
			(stroke
				(width 0.1)
				(type default)
			)
			(layer "B.Fab")
		)
		(fp_line
			(start 0.12065 -0.305054)
			(end 0.12065 -0.2794)
			(stroke
				(width 0.1)
				(type default)
			)
			(layer "B.Fab")
		)
		(fp_line
			(start 0.12065 -0.2794)
			(end -0.12065 -0.2794)
			(stroke
				(width 0.1)
				(type default)
			)
			(layer "B.Fab")
		)
		(fp_line
			(start 0.12065 0.2794)
			(end 0.12065 0.3048)
			(stroke
				(width 0.1)
				(type default)
			)
			(layer "B.Fab")
		)
		(fp_line
			(start 0.12065 0.3048)
			(end 0.67945 0.3048)
			(stroke
				(width 0.1)
				(type default)
			)
			(layer "B.Fab")
		)
		(fp_line
			(start 0.67945 -0.305054)
			(end 0.12065 -0.305054)
			(stroke
				(width 0.1)
				(type default)
			)
			(layer "B.Fab")
		)
		(fp_line
			(start 0.67945 0.3048)
			(end 0.67945 -0.305054)
			(stroke
				(width 0.1)
				(type default)
			)
			(layer "B.Fab")
		)
		(pad "1" smd circle
			(at 0.40005 0 180)
			(size 0 0)
			(layers "B.Cu" "B.Mask" "B.Paste")
			(net "PVDD11_S3_P1")
		)
		(pad "2" smd circle
			(at -0.40005 0 180)
			(size 0 0)
			(layers "B.Cu" "B.Mask" "B.Paste")
			(net "GND")
		)
	)
	(footprint ""
		(layer "B.Cu")
		(at 351.612454 -261.17931 180)
		(property "Reference" "C2596"
			(at 0 0 0)
			(layer "B.SilkS")
			(hide yes)
			(effects
				(font
					(size 1.27 1.27)
				)
				(justify mirror)
			)
		)
		(property "Value" ""
			(at 0 0 0)
			(layer "B.Fab")
			(effects
				(font
					(size 1.27 1.27)
				)
				(justify mirror)
			)
		)
		(duplicate_pad_numbers_are_jumpers no)
		(fp_line
			(start 0.7874 0.4064)
			(end 0.7874 -0.4064)
			(stroke
				(width 0.1524)
				(type default)
			)
			(layer "B.SilkS")
		)
		(fp_line
			(start 0.7874 -0.4064)
			(end -0.7874 -0.4064)
			(stroke
				(width 0.1524)
				(type default)
			)
			(layer "B.SilkS")
		)
		(fp_line
			(start -0.7874 0.4064)
			(end 0.7874 0.4064)
			(stroke
				(width 0.1524)
				(type default)
			)
			(layer "B.SilkS")
		)
		(fp_line
			(start -0.7874 -0.4064)
			(end -0.7874 0.4064)
			(stroke
				(width 0.1524)
				(type default)
			)
			(layer "B.SilkS")
		)
		(fp_line
			(start 0.67945 0.3048)
			(end 0.67945 -0.305054)
			(stroke
				(width 0.1)
				(type default)
			)
			(layer "B.Fab")
		)
		(fp_line
			(start 0.67945 -0.305054)
			(end 0.12065 -0.305054)
			(stroke
				(width 0.1)
				(type default)
			)
			(layer "B.Fab")
		)
		(fp_line
			(start 0.12065 0.3048)
			(end 0.67945 0.3048)
			(stroke
				(width 0.1)
				(type default)
			)
			(layer "B.Fab")
		)
		(fp_line
			(start 0.12065 0.2794)
			(end 0.12065 0.3048)
			(stroke
				(width 0.1)
				(type default)
			)
			(layer "B.Fab")
		)
		(fp_line
			(start 0.12065 -0.2794)
			(end -0.12065 -0.2794)
			(stroke
				(width 0.1)
				(type default)
			)
			(layer "B.Fab")
		)
		(fp_line
			(start 0.12065 -0.305054)
			(end 0.12065 -0.2794)
			(stroke
				(width 0.1)
				(type default)
			)
			(layer "B.Fab")
		)
		(fp_line
			(start -0.120396 0.3048)
			(end -0.120396 0.2794)
			(stroke
				(width 0.1)
				(type default)
			)
			(layer "B.Fab")
		)
		(fp_line
			(start -0.120396 0.2794)
			(end 0.12065 0.2794)
			(stroke
				(width 0.1)
				(type default)
			)
			(layer "B.Fab")
		)
		(fp_line
			(start -0.12065 -0.2794)
			(end -0.12065 -0.3048)
			(stroke
				(width 0.1)
				(type default)
			)
			(layer "B.Fab")
		)
		(fp_line
			(start -0.12065 -0.3048)
			(end -0.67945 -0.3048)
			(stroke
				(width 0.1)
				(type default)
			)
			(layer "B.Fab")
		)
		(fp_line
			(start -0.67945 0.3048)
			(end -0.120396 0.3048)
			(stroke
				(width 0.1)
				(type default)
			)
			(layer "B.Fab")
		)
		(fp_line
			(start -0.67945 -0.3048)
			(end -0.67945 0.3048)
			(stroke
				(width 0.1)
				(type default)
			)
			(layer "B.Fab")
		)
		(pad "1" smd circle
			(at 0.40005 0)
			(size 0 0)
			(layers "B.Cu" "B.Mask" "B.Paste")
			(net "PVDDCR_SOC_P0")
		)
		(pad "2" smd circle
			(at -0.40005 0)
			(size 0 0)
			(layers "B.Cu" "B.Mask" "B.Paste")
			(net "GND")
		)
	)
	(footprint ""
		(layer "B.Cu")
		(at 124.218446 -388.011162 -90)
		(property "Reference" "C447"
			(at 0 0 90)
			(layer "B.SilkS")
			(hide yes)
			(effects
				(font
					(size 1.27 1.27)
				)
				(justify mirror)
			)
		)
		(property "Value" ""
			(at 0 0 90)
			(layer "B.Fab")
			(effects
				(font
					(size 1.27 1.27)
				)
				(justify mirror)
			)
		)
		(duplicate_pad_numbers_are_jumpers no)
		(fp_line
			(start -0.299974 0.150114)
			(end 0.299974 0.150114)
			(stroke
				(width 0.1)
				(type default)
			)
			(layer "B.Fab")
		)
		(fp_line
			(start 0.299974 0.150114)
			(end 0.299974 -0.150114)
			(stroke
				(width 0.1)
				(type default)
			)
			(layer "B.Fab")
		)
		(fp_line
			(start -0.299974 -0.150114)
			(end -0.299974 0.150114)
			(stroke
				(width 0.1)
				(type default)
			)
			(layer "B.Fab")
		)
		(fp_line
			(start 0.299974 -0.150114)
			(end -0.299974 -0.150114)
			(stroke
				(width 0.1)
				(type default)
			)
			(layer "B.Fab")
		)
		(pad "1" smd rect
			(at 0.2667 0 90)
			(size 0.3048 0.381)
			(layers "B.Cu" "B.Mask" "B.Paste")
			(net "P1V8_CPU1_RT3_1A")
		)
		(pad "2" smd rect
			(at -0.2667 0 90)
			(size 0.3048 0.381)
			(layers "B.Cu" "B.Mask" "B.Paste")
			(net "GND")
		)
	)
	(footprint ""
		(layer "B.Cu")
		(at 358.796082 -257.744976 180)
		(property "Reference" "C3889"
			(at 0 0 0)
			(layer "B.SilkS")
			(hide yes)
			(effects
				(font
					(size 1.27 1.27)
				)
				(justify mirror)
			)
		)
		(property "Value" ""
			(at 0 0 0)
			(layer "B.Fab")
			(effects
				(font
					(size 1.27 1.27)
				)
				(justify mirror)
			)
		)
		(duplicate_pad_numbers_are_jumpers no)
		(fp_line
			(start 0.7874 0.4064)
			(end 0.7874 -0.4064)
			(stroke
				(width 0.1524)
				(type default)
			)
			(layer "B.SilkS")
		)
		(fp_line
			(start 0.7874 -0.4064)
			(end -0.7874 -0.4064)
			(stroke
				(width 0.1524)
				(type default)
			)
			(layer "B.SilkS")
		)
		(fp_line
			(start -0.7874 0.4064)
			(end 0.7874 0.4064)
			(stroke
				(width 0.1524)
				(type default)
			)
			(layer "B.SilkS")
		)
		(fp_line
			(start -0.7874 -0.4064)
			(end -0.7874 0.4064)
			(stroke
				(width 0.1524)
				(type default)
			)
			(layer "B.SilkS")
		)
		(fp_line
			(start 0.67945 0.3048)
			(end 0.67945 -0.305054)
			(stroke
				(width 0.1)
				(type default)
			)
			(layer "B.Fab")
		)
		(fp_line
			(start 0.67945 -0.305054)
			(end 0.12065 -0.305054)
			(stroke
				(width 0.1)
				(type default)
			)
			(layer "B.Fab")
		)
		(fp_line
			(start 0.12065 0.3048)
			(end 0.67945 0.3048)
			(stroke
				(width 0.1)
				(type default)
			)
			(layer "B.Fab")
		)
		(fp_line
			(start 0.12065 0.2794)
			(end 0.12065 0.3048)
			(stroke
				(width 0.1)
				(type default)
			)
			(layer "B.Fab")
		)
		(fp_line
			(start 0.12065 -0.2794)
			(end -0.12065 -0.2794)
			(stroke
				(width 0.1)
				(type default)
			)
			(layer "B.Fab")
		)
		(fp_line
			(start 0.12065 -0.305054)
			(end 0.12065 -0.2794)
			(stroke
				(width 0.1)
				(type default)
			)
			(layer "B.Fab")
		)
		(fp_line
			(start -0.120396 0.3048)
			(end -0.120396 0.2794)
			(stroke
				(width 0.1)
				(type default)
			)
			(layer "B.Fab")
		)
		(fp_line
			(start -0.120396 0.2794)
			(end 0.12065 0.2794)
			(stroke
				(width 0.1)
				(type default)
			)
			(layer "B.Fab")
		)
		(fp_line
			(start -0.12065 -0.2794)
			(end -0.12065 -0.3048)
			(stroke
				(width 0.1)
				(type default)
			)
			(layer "B.Fab")
		)
		(fp_line
			(start -0.12065 -0.3048)
			(end -0.67945 -0.3048)
			(stroke
				(width 0.1)
				(type default)
			)
			(layer "B.Fab")
		)
		(fp_line
			(start -0.67945 0.3048)
			(end -0.120396 0.3048)
			(stroke
				(width 0.1)
				(type default)
			)
			(layer "B.Fab")
		)
		(fp_line
			(start -0.67945 -0.3048)
			(end -0.67945 0.3048)
			(stroke
				(width 0.1)
				(type default)
			)
			(layer "B.Fab")
		)
		(pad "1" smd circle
			(at 0.40005 0)
			(size 0 0)
			(layers "B.Cu" "B.Mask" "B.Paste")
			(net "PVDDCR_SOC_P0")
		)
		(pad "2" smd circle
			(at -0.40005 0)
			(size 0 0)
			(layers "B.Cu" "B.Mask" "B.Paste")
			(net "GND")
		)
	)
	(footprint ""
		(layer "B.Cu")
		(at 408.316684 -332.118462 180)
		(property "Reference" "R5026"
			(at 0 0 0)
			(layer "B.SilkS")
			(hide yes)
			(effects
				(font
					(size 1.27 1.27)
				)
				(justify mirror)
			)
		)
		(property "Value" ""
			(at 0 0 0)
			(layer "B.Fab")
			(effects
				(font
					(size 1.27 1.27)
				)
				(justify mirror)
			)
		)
		(duplicate_pad_numbers_are_jumpers no)
		(fp_line
			(start 0.7874 0.4064)
			(end 0.7874 -0.4064)
			(stroke
				(width 0.1524)
				(type default)
			)
			(layer "B.SilkS")
		)
		(fp_line
			(start 0.7874 -0.4064)
			(end -0.7874 -0.4064)
			(stroke
				(width 0.1524)
				(type default)
			)
			(layer "B.SilkS")
		)
		(fp_line
			(start -0.7874 0.4064)
			(end 0.7874 0.4064)
			(stroke
				(width 0.1524)
				(type default)
			)
			(layer "B.SilkS")
		)
		(fp_line
			(start -0.7874 -0.4064)
			(end -0.7874 0.4064)
			(stroke
				(width 0.1524)
				(type default)
			)
			(layer "B.SilkS")
		)
		(fp_line
			(start 0.67945 0.3048)
			(end 0.67945 -0.305054)
			(stroke
				(width 0.1)
				(type default)
			)
			(layer "B.Fab")
		)
		(fp_line
			(start 0.67945 -0.305054)
			(end 0.12065 -0.305054)
			(stroke
				(width 0.1)
				(type default)
			)
			(layer "B.Fab")
		)
		(fp_line
			(start 0.12065 0.3048)
			(end 0.67945 0.3048)
			(stroke
				(width 0.1)
				(type default)
			)
			(layer "B.Fab")
		)
		(fp_line
			(start 0.12065 0.2794)
			(end 0.12065 0.3048)
			(stroke
				(width 0.1)
				(type default)
			)
			(layer "B.Fab")
		)
		(fp_line
			(start 0.12065 -0.2794)
			(end -0.12065 -0.2794)
			(stroke
				(width 0.1)
				(type default)
			)
			(layer "B.Fab")
		)
		(fp_line
			(start 0.12065 -0.305054)
			(end 0.12065 -0.2794)
			(stroke
				(width 0.1)
				(type default)
			)
			(layer "B.Fab")
		)
		(fp_line
			(start -0.120396 0.3048)
			(end -0.120396 0.2794)
			(stroke
				(width 0.1)
				(type default)
			)
			(layer "B.Fab")
		)
		(fp_line
			(start -0.120396 0.2794)
			(end 0.12065 0.2794)
			(stroke
				(width 0.1)
				(type default)
			)
			(layer "B.Fab")
		)
		(fp_line
			(start -0.12065 -0.2794)
			(end -0.12065 -0.3048)
			(stroke
				(width 0.1)
				(type default)
			)
			(layer "B.Fab")
		)
		(fp_line
			(start -0.12065 -0.3048)
			(end -0.67945 -0.3048)
			(stroke
				(width 0.1)
				(type default)
			)
			(layer "B.Fab")
		)
		(fp_line
			(start -0.67945 0.3048)
			(end -0.120396 0.3048)
			(stroke
				(width 0.1)
				(type default)
			)
			(layer "B.Fab")
		)
		(fp_line
			(start -0.67945 -0.3048)
			(end -0.67945 0.3048)
			(stroke
				(width 0.1)
				(type default)
			)
			(layer "B.Fab")
		)
		(pad "1" smd circle
			(at 0.40005 0)
			(size 0 0)
			(layers "B.Cu" "B.Mask" "B.Paste")
			(net "GND")
		)
		(pad "2" smd circle
			(at -0.40005 0)
			(size 0 0)
			(layers "B.Cu" "B.Mask" "B.Paste")
			(net "FM_SMM_CRASHDUMP")
		)
	)
	(footprint ""
		(layer "B.Cu")
		(at 96.886522 -150.698962 -90)
		(property "Reference" "PR530"
			(at 0 0 90)
			(layer "B.SilkS")
			(hide yes)
			(effects
				(font
					(size 1.27 1.27)
				)
				(justify mirror)
			)
		)
		(property "Value" ""
			(at 0 0 90)
			(layer "B.Fab")
			(effects
				(font
					(size 1.27 1.27)
				)
				(justify mirror)
			)
		)
		(duplicate_pad_numbers_are_jumpers no)
		(fp_line
			(start -0.7874 0.4064)
			(end 0.7874 0.4064)
			(stroke
				(width 0.1524)
				(type default)
			)
			(layer "B.SilkS")
		)
		(fp_line
			(start 0.7874 0.4064)
			(end 0.7874 -0.4064)
			(stroke
				(width 0.1524)
				(type default)
			)
			(layer "B.SilkS")
		)
		(fp_line
			(start -0.7874 -0.4064)
			(end -0.7874 0.4064)
			(stroke
				(width 0.1524)
				(type default)
			)
			(layer "B.SilkS")
		)
		(fp_line
			(start 0.7874 -0.4064)
			(end -0.7874 -0.4064)
			(stroke
				(width 0.1524)
				(type default)
			)
			(layer "B.SilkS")
		)
		(fp_line
			(start -0.67945 0.3048)
			(end -0.120396 0.3048)
			(stroke
				(width 0.1)
				(type default)
			)
			(layer "B.Fab")
		)
		(fp_line
			(start -0.120396 0.3048)
			(end -0.120396 0.2794)
			(stroke
				(width 0.1)
				(type default)
			)
			(layer "B.Fab")
		)
		(fp_line
			(start 0.12065 0.3048)
			(end 0.67945 0.3048)
			(stroke
				(width 0.1)
				(type default)
			)
			(layer "B.Fab")
		)
		(fp_line
			(start 0.67945 0.3048)
			(end 0.67945 -0.305054)
			(stroke
				(width 0.1)
				(type default)
			)
			(layer "B.Fab")
		)
		(fp_line
			(start -0.120396 0.2794)
			(end 0.12065 0.2794)
			(stroke
				(width 0.1)
				(type default)
			)
			(layer "B.Fab")
		)
		(fp_line
			(start 0.12065 0.2794)
			(end 0.12065 0.3048)
			(stroke
				(width 0.1)
				(type default)
			)
			(layer "B.Fab")
		)
		(fp_line
			(start -0.12065 -0.2794)
			(end -0.12065 -0.3048)
			(stroke
				(width 0.1)
				(type default)
			)
			(layer "B.Fab")
		)
		(fp_line
			(start 0.12065 -0.2794)
			(end -0.12065 -0.2794)
			(stroke
				(width 0.1)
				(type default)
			)
			(layer "B.Fab")
		)
		(fp_line
			(start -0.67945 -0.3048)
			(end -0.67945 0.3048)
			(stroke
				(width 0.1)
				(type default)
			)
			(layer "B.Fab")
		)
		(fp_line
			(start -0.12065 -0.3048)
			(end -0.67945 -0.3048)
			(stroke
				(width 0.1)
				(type default)
			)
			(layer "B.Fab")
		)
		(fp_line
			(start 0.12065 -0.305054)
			(end 0.12065 -0.2794)
			(stroke
				(width 0.1)
				(type default)
			)
			(layer "B.Fab")
		)
		(fp_line
			(start 0.67945 -0.305054)
			(end 0.12065 -0.305054)
			(stroke
				(width 0.1)
				(type default)
			)
			(layer "B.Fab")
		)
		(pad "1" smd circle
			(at 0.40005 0 90)
			(size 0 0)
			(layers "B.Cu" "B.Mask" "B.Paste")
			(net "NC_PVDDCR_CPU0_P1_IMON7")
		)
		(pad "2" smd circle
			(at -0.40005 0 90)
			(size 0 0)
			(layers "B.Cu" "B.Mask" "B.Paste")
			(net "GND")
		)
	)
)
